FILE_TYPE = MULTI_PHYS_TABLE;
PART 'SCONN75K_H17033002'
{==========================================================================================================================================================================================================}
:PACK_TYPE | MATERIAL | PART_NUMBER     = EnvComp | PART_NUMBER  | JEDEC_TYPE             | DESCRIPTION                                          | CLASS | COMPONENT_TYPE | HEIGHT     | LPID      | SPEED_URL       | Status |RPL| AML | Bus_Unit | Days ;
{==========================================================================================================================================================================================================}
'SMT'      | 'SCONN'  | 'H17033-002'(!) = 'YES;YES;YES;UNK;ok;VLD' | 'H17033-002' | 'SCONN75K_H17033002'   | '(IO USE SYM_1) CONN,CEDG,67P,PCIE,RA,0.5MM,SMT,BK'  | 'IO'  | 'SMTCONN'      | '0.343 IN' | '3020'    | 'http://speed.intel.com:8081/speed/module/pdm/item/pdm_item_detail_direct.asp?item_cde=H17033-002&item_rev=01&url_param=unused' | 'Design' | 'NO' | '1' | 'SMO_BOARDS' | '???' 
'SMT'      | 'EMPTY'  | 'H17033-002'(!) = 'YES;YES;YES;UNK;ok;VLD' | 'H17033-002' | 'SCONN75K_H17033002'   | '(IO USE SYM_1) CONN,CEDG,67P,PCIE,RA,0.5MM,SMT,BK'  | 'IO'  | 'SMTCONN'      | '0.343 IN' | '3020'    | 'http://speed.intel.com:8081/speed/module/pdm/item/pdm_item_detail_direct.asp?item_cde=H17033-002&item_rev=01&url_param=unused' | 'Design' | 'NO' | '1' | 'SMO_BOARDS' | '???' 
'SMT1'     | 'SCONN'  | 'H17033-002'(!) = 'YES;YES;YES;UNK;ok;VLD' | 'H17033-002' | 'SCONN75K_H17033002'   | '(PCIE USE SYM_2) CONN,CEDG,67P,PCIE,RA,0.5MM,SMT,BK'| 'IO'  | 'SMTCONN'      | '0.343 IN' | '3020'    | 'http://speed.intel.com:8081/speed/module/pdm/item/pdm_item_detail_direct.asp?item_cde=H17033-002&item_rev=01&url_param=unused' | 'Design' | 'NO' | '1' | 'SMO_BOARDS' | '???' 
'SMT1'     | 'EMPTY'  | 'H17033-002'(!) = 'YES;YES;YES;UNK;ok;VLD' | 'H17033-002' | 'SCONN75K_H17033002'   | '(PCIE USE SYM_2) CONN,CEDG,67P,PCIE,RA,0.5MM,SMT,BK'| 'IO'  | 'SMTCONN'      | '0.343 IN' | '3020'    | 'http://speed.intel.com:8081/speed/module/pdm/item/pdm_item_detail_direct.asp?item_cde=H17033-002&item_rev=01&url_param=unused' | 'Design' | 'NO' | '1' | 'SMO_BOARDS' | '???' 
END_PART
END.
